# S9S_MB_2U (Grand Teton) — schematic netlist excerpt (pin names and nets, part order shuffled) for the footprints in the layout excerpt that follows; sources: Cadence DE-HDL packaged netlist, KiCad conversion of 03242023_DA0F0TMBIJ0_F0T_Motherboard_J_brd_V01_OCP.brd

R1692  Q_RES  100K 1% CHIP  pkg 0402LF  page 244 : A = PWRGD_DSW_PWROK_R1 ; B = GND
PR3912  Q_RES  120K 1% CHIP  pkg 0402LF  page 302 : A = AGND_HSC ; B = HSC_MODE_2
C679  Q_CAP_DIFFBUS  DIFF BUS_0.22UF 6.3V 20% X6S  pkg C0201  page 177 : \1\ = P5E_CPU1_PE4_TX_C_DP<15> ; \2\ = P5E_CPU1_PE4_TX_DP<15>

(kicad_pcb
	(version 20260206)
	(generator "pcbnew")
	(generator_version "10.0")
	(general
		(thickness 1.6)
		(legacy_teardrops no)
	)
	(paper "A4")
	(title_block
		(title "03242023_DA0F0TMBIJ0_F0T_Motherboard_J_brd_V01_OCP.brd")
		(comment 1 "Grand Teton / footprints 521-523 of 6105")
	)
	(layers
		(0 "F.Cu" signal "TOP")
		(4 "In1.Cu" signal "GND")
		(6 "In2.Cu" signal "IN1")
		(8 "In3.Cu" signal "GND1")
		(10 "In4.Cu" signal "IN2")
		(12 "In5.Cu" signal "GND2")
		(14 "In6.Cu" signal "IN3")
		(16 "In7.Cu" signal "GND3")
		(18 "In8.Cu" signal "VCC")
		(20 "In9.Cu" signal "VCC1")
		(22 "In10.Cu" signal "GND4")
		(24 "In11.Cu" signal "IN4")
		(26 "In12.Cu" signal "GND5")
		(28 "In13.Cu" signal "IN5")
		(30 "In14.Cu" signal "GND6")
		(32 "In15.Cu" signal "IN6")
		(34 "In16.Cu" signal "GND7")
		(2 "B.Cu" signal "BOTTOM")
		(9 "F.Adhes" user "F.Adhesive")
		(11 "B.Adhes" user "B.Adhesive")
		(13 "F.Paste" user "Package Geometry/Pastemask Top")
		(15 "B.Paste" user "Package Geometry/Pastemask Bottom")
		(5 "F.SilkS" user "Ref Des/Silkscreen Top")
		(7 "B.SilkS" user "Ref Des/Silkscreen Bottom")
		(1 "F.Mask" user "Board Geometry/Soldermask Top")
		(3 "B.Mask" user "Board Geometry/Soldermask Bottom")
		(17 "Dwgs.User" user "User.Drawings")
		(19 "Cmts.User" user "User.Comments")
		(21 "Eco1.User" user "User.Eco1")
		(23 "Eco2.User" user "User.Eco2")
		(25 "Edge.Cuts" user "Board Geometry/Outline")
		(27 "Margin" user)
		(31 "F.CrtYd" user "Package Geometry/Place Bound Top")
		(29 "B.CrtYd" user "Package Geometry/Place Bound Bottom")
		(35 "F.Fab" user "Ref Des/Assembly Top")
		(33 "B.Fab" user "Ref Des/Assembly Bottom")
	)
	(footprint ""
		(layer "F.Cu")
		(at 96.163638 -408.517344 -90)
		(property "Reference" "C679"
			(at 0 0 270)
			(layer "F.SilkS")
			(hide yes)
			(effects
				(font
					(size 1.27 1.27)
				)
			)
		)
		(property "Value" ""
			(at 0 0 270)
			(layer "F.Fab")
			(effects
				(font
					(size 1.27 1.27)
				)
			)
		)
		(duplicate_pad_numbers_are_jumpers no)
		(fp_line
			(start -0.299974 0.150114)
			(end -0.299974 -0.150114)
			(stroke
				(width 0.1)
				(type default)
			)
			(layer "F.Fab")
		)
		(fp_line
			(start 0.299974 0.150114)
			(end -0.299974 0.150114)
			(stroke
				(width 0.1)
				(type default)
			)
			(layer "F.Fab")
		)
		(fp_line
			(start -0.299974 -0.150114)
			(end 0.299974 -0.150114)
			(stroke
				(width 0.1)
				(type default)
			)
			(layer "F.Fab")
		)
		(fp_line
			(start 0.299974 -0.150114)
			(end 0.299974 0.150114)
			(stroke
				(width 0.1)
				(type default)
			)
			(layer "F.Fab")
		)
		(pad "1" smd rect
			(at -0.2667 0 270)
			(size 0.3048 0.381)
			(layers "F.Cu" "F.Mask" "F.Paste")
			(net "P5E_CPU1_PE4_TX_C_DP<15>")
		)
		(pad "2" smd rect
			(at 0.2667 0 270)
			(size 0.3048 0.381)
			(layers "F.Cu" "F.Mask" "F.Paste")
			(net "P5E_CPU1_PE4_TX_DP<15>")
		)
	)
	(footprint ""
		(layer "F.Cu")
		(at 216.065608 -407.871422 180)
		(property "Reference" "PR3912"
			(at 0 0 180)
			(layer "F.SilkS")
			(hide yes)
			(effects
				(font
					(size 1.27 1.27)
				)
			)
		)
		(property "Value" ""
			(at 0 0 180)
			(layer "F.Fab")
			(effects
				(font
					(size 1.27 1.27)
				)
			)
		)
		(duplicate_pad_numbers_are_jumpers no)
		(fp_line
			(start 0.7874 0.4064)
			(end -0.7874 0.4064)
			(stroke
				(width 0.1524)
				(type default)
			)
			(layer "F.SilkS")
		)
		(fp_line
			(start 0.7874 -0.4064)
			(end 0.7874 0.4064)
			(stroke
				(width 0.1524)
				(type default)
			)
			(layer "F.SilkS")
		)
		(fp_line
			(start -0.7874 0.4064)
			(end -0.7874 -0.4064)
			(stroke
				(width 0.1524)
				(type default)
			)
			(layer "F.SilkS")
		)
		(fp_line
			(start -0.7874 -0.4064)
			(end 0.7874 -0.4064)
			(stroke
				(width 0.1524)
				(type default)
			)
			(layer "F.SilkS")
		)
		(fp_line
			(start 0.67945 0.3048)
			(end 0.120396 0.3048)
			(stroke
				(width 0.1)
				(type default)
			)
			(layer "F.Fab")
		)
		(fp_line
			(start 0.67945 -0.3048)
			(end 0.67945 0.3048)
			(stroke
				(width 0.1)
				(type default)
			)
			(layer "F.Fab")
		)
		(fp_line
			(start 0.12065 -0.2794)
			(end 0.12065 -0.3048)
			(stroke
				(width 0.1)
				(type default)
			)
			(layer "F.Fab")
		)
		(fp_line
			(start 0.12065 -0.3048)
			(end 0.67945 -0.3048)
			(stroke
				(width 0.1)
				(type default)
			)
			(layer "F.Fab")
		)
		(fp_line
			(start 0.120396 0.3048)
			(end 0.120396 0.2794)
			(stroke
				(width 0.1)
				(type default)
			)
			(layer "F.Fab")
		)
		(fp_line
			(start 0.120396 0.2794)
			(end -0.12065 0.2794)
			(stroke
				(width 0.1)
				(type default)
			)
			(layer "F.Fab")
		)
		(fp_line
			(start -0.12065 0.3048)
			(end -0.67945 0.3048)
			(stroke
				(width 0.1)
				(type default)
			)
			(layer "F.Fab")
		)
		(fp_line
			(start -0.12065 0.2794)
			(end -0.12065 0.3048)
			(stroke
				(width 0.1)
				(type default)
			)
			(layer "F.Fab")
		)
		(fp_line
			(start -0.12065 -0.2794)
			(end 0.12065 -0.2794)
			(stroke
				(width 0.1)
				(type default)
			)
			(layer "F.Fab")
		)
		(fp_line
			(start -0.12065 -0.305054)
			(end -0.12065 -0.2794)
			(stroke
				(width 0.1)
				(type default)
			)
			(layer "F.Fab")
		)
		(fp_line
			(start -0.67945 0.3048)
			(end -0.67945 -0.305054)
			(stroke
				(width 0.1)
				(type default)
			)
			(layer "F.Fab")
		)
		(fp_line
			(start -0.67945 -0.305054)
			(end -0.12065 -0.305054)
			(stroke
				(width 0.1)
				(type default)
			)
			(layer "F.Fab")
		)
		(pad "1" smd circle
			(at -0.40005 0 180)
			(size 0 0)
			(layers "F.Cu" "F.Mask" "F.Paste")
			(net "AGND_HSC")
		)
		(pad "2" smd circle
			(at 0.40005 0 180)
			(size 0 0)
			(layers "F.Cu" "F.Mask" "F.Paste")
			(net "HSC_MODE_2")
		)
	)
	(footprint ""
		(layer "F.Cu")
		(at 218.08948 -126.761748)
		(property "Reference" "R1692"
			(at 0 0 0)
			(layer "F.SilkS")
			(hide yes)
			(effects
				(font
					(size 1.27 1.27)
				)
			)
		)
		(property "Value" ""
			(at 0 0 0)
			(layer "F.Fab")
			(effects
				(font
					(size 1.27 1.27)
				)
			)
		)
		(duplicate_pad_numbers_are_jumpers no)
		(fp_line
			(start -0.7874 -0.4064)
			(end 0.7874 -0.4064)
			(stroke
				(width 0.1524)
				(type default)
			)
			(layer "F.SilkS")
		)
		(fp_line
			(start -0.7874 0.4064)
			(end -0.7874 -0.4064)
			(stroke
				(width 0.1524)
				(type default)
			)
			(layer "F.SilkS")
		)
		(fp_line
			(start 0.7874 -0.4064)
			(end 0.7874 0.4064)
			(stroke
				(width 0.1524)
				(type default)
			)
			(layer "F.SilkS")
		)
		(fp_line
			(start 0.7874 0.4064)
			(end -0.7874 0.4064)
			(stroke
				(width 0.1524)
				(type default)
			)
			(layer "F.SilkS")
		)
		(fp_line
			(start -0.67945 -0.305054)
			(end -0.12065 -0.305054)
			(stroke
				(width 0.1)
				(type default)
			)
			(layer "F.Fab")
		)
		(fp_line
			(start -0.67945 0.3048)
			(end -0.67945 -0.305054)
			(stroke
				(width 0.1)
				(type default)
			)
			(layer "F.Fab")
		)
		(fp_line
			(start -0.12065 -0.305054)
			(end -0.12065 -0.2794)
			(stroke
				(width 0.1)
				(type default)
			)
			(layer "F.Fab")
		)
		(fp_line
			(start -0.12065 -0.2794)
			(end 0.12065 -0.2794)
			(stroke
				(width 0.1)
				(type default)
			)
			(layer "F.Fab")
		)
		(fp_line
			(start -0.12065 0.2794)
			(end -0.12065 0.3048)
			(stroke
				(width 0.1)
				(type default)
			)
			(layer "F.Fab")
		)
		(fp_line
			(start -0.12065 0.3048)
			(end -0.67945 0.3048)
			(stroke
				(width 0.1)
				(type default)
			)
			(layer "F.Fab")
		)
		(fp_line
			(start 0.120396 0.2794)
			(end -0.12065 0.2794)
			(stroke
				(width 0.1)
				(type default)
			)
			(layer "F.Fab")
		)
		(fp_line
			(start 0.120396 0.3048)
			(end 0.120396 0.2794)
			(stroke
				(width 0.1)
				(type default)
			)
			(layer "F.Fab")
		)
		(fp_line
			(start 0.12065 -0.3048)
			(end 0.67945 -0.3048)
			(stroke
				(width 0.1)
				(type default)
			)
			(layer "F.Fab")
		)
		(fp_line
			(start 0.12065 -0.2794)
			(end 0.12065 -0.3048)
			(stroke
				(width 0.1)
				(type default)
			)
			(layer "F.Fab")
		)
		(fp_line
			(start 0.67945 -0.3048)
			(end 0.67945 0.3048)
			(stroke
				(width 0.1)
				(type default)
			)
			(layer "F.Fab")
		)
		(fp_line
			(start 0.67945 0.3048)
			(end 0.120396 0.3048)
			(stroke
				(width 0.1)
				(type default)
			)
			(layer "F.Fab")
		)
		(pad "1" smd circle
			(at -0.40005 0)
			(size 0 0)
			(layers "F.Cu" "F.Mask" "F.Paste")
			(net "PWRGD_DSW_PWROK_R1")
		)
		(pad "2" smd circle
			(at 0.40005 0)
			(size 0 0)
			(layers "F.Cu" "F.Mask" "F.Paste")
			(net "GND")
		)
	)
)
